(kicad_pcb
	(version 20241229)
	(generator "pcbnew")
	(generator_version "9.0")
	(general
		(thickness 1.711)
		(legacy_teardrops no)
	)
	(paper "A4")
	(title_block
		(title "Antmicro Baseboard for Jetson AGX Thor")
		(date "2026-02-18")
		(rev "1.1.0")
		(company "Antmicro Ltd")
		(comment 1 "www.antmicro.com")
		(comment 9 "footprints 1066-1070 of 1170")
	)
	(layers
		(0 "F.Cu" signal)
		(4 "In1.Cu" signal)
		(6 "In2.Cu" signal)
		(8 "In3.Cu" signal)
		(10 "In4.Cu" jumper)
		(12 "In5.Cu" signal)
		(14 "In6.Cu" signal)
		(16 "In7.Cu" signal)
		(18 "In8.Cu" signal)
		(2 "B.Cu" signal)
		(9 "F.Adhes" user "F.Adhesive")
		(11 "B.Adhes" user "B.Adhesive")
		(13 "F.Paste" user)
		(15 "B.Paste" user)
		(5 "F.SilkS" user "F.Silkscreen")
		(7 "B.SilkS" user "B.Silkscreen")
		(1 "F.Mask" user)
		(3 "B.Mask" user)
		(17 "Dwgs.User" user "User.Drawings")
		(19 "Cmts.User" user "User.Comments")
		(21 "Eco1.User" user "User.Eco1")
		(23 "Eco2.User" user "User.Eco2")
		(25 "Edge.Cuts" user)
		(27 "Margin" user)
		(31 "F.CrtYd" user "F.Courtyard")
		(29 "B.CrtYd" user "B.Courtyard")
		(35 "F.Fab" user)
		(33 "B.Fab" user)
	)
	(footprint "antmicro-footprints:R_0402_1005Metric"
		(layer "B.Cu")
		(at 95 55.5 -90)
		(descr "Resistor SMD 0402")
		(tags "resistor SMD 0402")
		(property "Reference" "R307"
			(at 1 -0.5 90)
			(layer "B.SilkS")
			(effects
				(font
					(size 0.7 0.7)
					(thickness 0.15)
				)
				(justify left bottom mirror)
			)
		)
		(property "Value" "R_10k_0402"
			(at -1.011843 -1.772046 90)
			(layer "B.Fab")
			(effects
				(font
					(size 0.7 0.7)
					(thickness 0.15)
				)
				(justify left bottom mirror)
			)
		)
		(property "Datasheet" "https://www.bourns.com/docs/product-datasheets/cr.pdf"
			(at 0 0 90)
			(layer "B.Fab")
			(hide yes)
			(effects
				(font
					(size 1.27 1.27)
					(thickness 0.15)
				)
				(justify mirror)
			)
		)
		(property "Description" "SMD Chip Resistor, 10 kohm, ± 1%, 62.5 mW, 0402 [1005 Metric], Thick Film, General Purpose"
			(at 0 0 90)
			(layer "B.Fab")
			(hide yes)
			(effects
				(font
					(size 1.27 1.27)
					(thickness 0.15)
				)
				(justify mirror)
			)
		)
		(property "MPN" "CR0402-FX-1002GLF"
			(at 0 0 90)
			(unlocked yes)
			(layer "B.Fab")
			(hide yes)
			(effects
				(font
					(size 1 1)
					(thickness 0.15)
				)
				(justify mirror)
			)
		)
		(property "Manufacturer" "Bourns"
			(at 0 0 90)
			(unlocked yes)
			(layer "B.Fab")
			(hide yes)
			(effects
				(font
					(size 1 1)
					(thickness 0.15)
				)
				(justify mirror)
			)
		)
		(property "License" "Apache-2.0"
			(at 0 0 90)
			(unlocked yes)
			(layer "B.Fab")
			(hide yes)
			(effects
				(font
					(size 1 1)
					(thickness 0.15)
				)
				(justify mirror)
			)
		)
		(property "Author" "Antmicro"
			(at 0 0 90)
			(unlocked yes)
			(layer "B.Fab")
			(hide yes)
			(effects
				(font
					(size 1 1)
					(thickness 0.15)
				)
				(justify mirror)
			)
		)
		(property "Val" "10k"
			(at 0 0 90)
			(unlocked yes)
			(layer "B.Fab")
			(hide yes)
			(effects
				(font
					(size 1 1)
					(thickness 0.15)
				)
				(justify mirror)
			)
		)
		(property "Tolerance" "1%"
			(at 0 0 90)
			(unlocked yes)
			(layer "B.Fab")
			(hide yes)
			(effects
				(font
					(size 1 1)
					(thickness 0.15)
				)
				(justify mirror)
			)
		)
		(sheetname "/SoM_Power/")
		(sheetfile "som_power.kicad_sch")
		(attr smd)
		(fp_poly
			(pts
				(xy -0.925 0.47) (xy 0.925 0.47) (xy 0.925 -0.47) (xy -0.925 -0.47)
			)
			(stroke
				(width 0.05)
				(type default)
			)
			(fill no)
			(layer "B.CrtYd")
		)
		(fp_poly
			(pts
				(xy -0.5 0.25) (xy 0.5 0.25) (xy 0.5 -0.25) (xy -0.5 -0.25)
			)
			(stroke
				(width 0.15)
				(type solid)
			)
			(fill no)
			(layer "B.Fab")
		)
		(fp_text user "${REFERENCE}"
			(at -0.95 -3.168 90)
			(layer "B.Fab")
			(effects
				(font
					(size 0.7 0.7)
					(thickness 0.15)
				)
				(justify left bottom mirror)
			)
		)
		(fp_text user "License: Apache-2.0"
			(at -0.949999 -5.169 90)
			(layer "B.Fab")
			(effects
				(font
					(size 0.7 0.7)
					(thickness 0.15)
				)
				(justify left bottom mirror)
			)
		)
		(fp_text user "Author: Antmicro"
			(at -0.95 -4.169 90)
			(layer "B.Fab")
			(effects
				(font
					(size 0.7 0.7)
					(thickness 0.15)
				)
				(justify left bottom mirror)
			)
		)
		(pad "1" smd roundrect
			(at -0.48 0 270)
			(size 0.59 0.64)
			(layers "B.Cu" "B.Mask" "B.Paste")
			(roundrect_rratio 0.25)
			(net 1 "GND")
			(pintype "passive")
		)
		(pad "2" smd roundrect
			(at 0.48 0 270)
			(size 0.59 0.64)
			(layers "B.Cu" "B.Mask" "B.Paste")
			(roundrect_rratio 0.25)
			(net 1036 "Net-(R307-Pad2)")
			(pintype "passive")
		)
	)
	(footprint "antmicro-footprints:R_0402_1005Metric"
		(layer "B.Cu")
		(at 64.1 70.4 90)
		(descr "Resistor SMD 0402")
		(tags "resistor SMD 0402")
		(property "Reference" "R399"
			(at -2.2 3.7 90)
			(layer "B.SilkS")
			(effects
				(font
					(size 0.7 0.7)
					(thickness 0.15)
				)
				(justify right top mirror)
			)
		)
		(property "Value" "R_0R_0402"
			(at -1.011843 -1.772047 90)
			(layer "B.Fab")
			(effects
				(font
					(size 0.7 0.7)
					(thickness 0.15)
				)
				(justify right top mirror)
			)
		)
		(property "Datasheet" "https://industrial.panasonic.com/cdbs/www-data/pdf/RDA0000/AOA0000C301.pdf"
			(at 0 0 90)
			(layer "B.Fab")
			(hide yes)
			(effects
				(font
					(size 1.27 1.27)
					(thickness 0.15)
				)
				(justify mirror)
			)
		)
		(property "Description" "SMD Chip Resistor, Jumper, 0 ohm, 100 mW, 0402 [1005 Metric], Thick Film, General Purpose"
			(at 0 0 90)
			(layer "B.Fab")
			(hide yes)
			(effects
				(font
					(size 1.27 1.27)
					(thickness 0.15)
				)
				(justify mirror)
			)
		)
		(property "MPN" "ERJ2GE0R00X"
			(at 0 0 270)
			(unlocked yes)
			(layer "B.Fab")
			(hide yes)
			(effects
				(font
					(size 1 1)
					(thickness 0.15)
				)
				(justify mirror)
			)
		)
		(property "Manufacturer" "Panasonic"
			(at 0 0 270)
			(unlocked yes)
			(layer "B.Fab")
			(hide yes)
			(effects
				(font
					(size 1 1)
					(thickness 0.15)
				)
				(justify mirror)
			)
		)
		(property "License" "Apache-2.0"
			(at 0 0 270)
			(unlocked yes)
			(layer "B.Fab")
			(hide yes)
			(effects
				(font
					(size 1 1)
					(thickness 0.15)
				)
				(justify mirror)
			)
		)
		(property "Author" "Antmicro"
			(at 0 0 270)
			(unlocked yes)
			(layer "B.Fab")
			(hide yes)
			(effects
				(font
					(size 1 1)
					(thickness 0.15)
				)
				(justify mirror)
			)
		)
		(property "Val" "0R"
			(at 0 0 270)
			(unlocked yes)
			(layer "B.Fab")
			(hide yes)
			(effects
				(font
					(size 1 1)
					(thickness 0.15)
				)
				(justify mirror)
			)
		)
		(property "Tolerance" "~"
			(at 0 0 270)
			(unlocked yes)
			(layer "B.Fab")
			(hide yes)
			(effects
				(font
					(size 1 1)
					(thickness 0.15)
				)
				(justify mirror)
			)
		)
		(property "Current" "1A"
			(at 0 0 270)
			(unlocked yes)
			(layer "B.Fab")
			(hide yes)
			(effects
				(font
					(size 1 1)
					(thickness 0.15)
				)
				(justify mirror)
			)
		)
		(sheetname "/CSI/")
		(sheetfile "csi.kicad_sch")
		(attr smd)
		(fp_rect
			(start -0.925 0.47)
			(end 0.925 -0.47)
			(stroke
				(width 0.05)
				(type default)
			)
			(fill no)
			(layer "B.CrtYd")
		)
		(fp_rect
			(start -0.5 0.25)
			(end 0.5 -0.25)
			(stroke
				(width 0.15)
				(type solid)
			)
			(fill no)
			(layer "B.Fab")
		)
		(fp_text user "License: Apache-2.0"
			(at -0.95 -5.169 90)
			(layer "B.Fab")
			(effects
				(font
					(size 0.7 0.7)
					(thickness 0.15)
				)
				(justify right top mirror)
			)
		)
		(fp_text user "${REFERENCE}"
			(at -0.95 -3.168 90)
			(layer "B.Fab")
			(effects
				(font
					(size 0.7 0.7)
					(thickness 0.15)
				)
				(justify right top mirror)
			)
		)
		(fp_text user "Author: Antmicro"
			(at -0.95 -4.169 90)
			(layer "B.Fab")
			(effects
				(font
					(size 0.7 0.7)
					(thickness 0.15)
				)
				(justify right top mirror)
			)
		)
		(pad "1" smd roundrect
			(at -0.48 0 90)
			(size 0.59 0.64)
			(layers "B.Cu" "B.Mask" "B.Paste")
			(roundrect_rratio 0.25)
			(net 1376 "Net-(J11-Pad41)")
			(pintype "passive")
		)
		(pad "2" smd roundrect
			(at 0.48 0 90)
			(size 0.59 0.64)
			(layers "B.Cu" "B.Mask" "B.Paste")
			(roundrect_rratio 0.25)
			(net 986 "/CSI/SDA_CAM1")
			(pintype "passive")
		)
	)
	(footprint "antmicro-footprints:TP_SMD_0.75mm"
		(layer "B.Cu")
		(at 156.7 140.7 -90)
		(property "Reference" "TP89"
			(at 0.5 -0.5 90)
			(layer "B.SilkS")
			(effects
				(font
					(size 0.7 0.7)
					(thickness 0.15)
				)
				(justify left bottom mirror)
			)
		)
		(property "Value" "TP_0.75mm_SMD"
			(at 0 -1.2 90)
			(layer "B.Fab")
			(effects
				(font
					(size 0.7 0.7)
					(thickness 0.15)
				)
				(justify left bottom mirror)
			)
		)
		(property "Description" "SMT test point"
			(at 0 0 90)
			(layer "B.Fab")
			(hide yes)
			(effects
				(font
					(size 1.27 1.27)
					(thickness 0.15)
				)
				(justify mirror)
			)
		)
		(property "MPN" ""
			(at 0 0 90)
			(unlocked yes)
			(layer "B.Fab")
			(hide yes)
			(effects
				(font
					(size 1 1)
					(thickness 0.15)
				)
				(justify mirror)
			)
		)
		(property "Manufacturer" ""
			(at 0 0 90)
			(unlocked yes)
			(layer "B.Fab")
			(hide yes)
			(effects
				(font
					(size 1 1)
					(thickness 0.15)
				)
				(justify mirror)
			)
		)
		(property "Author" "Antmicro"
			(at 0 0 90)
			(unlocked yes)
			(layer "B.Fab")
			(hide yes)
			(effects
				(font
					(size 1 1)
					(thickness 0.15)
				)
				(justify mirror)
			)
		)
		(property "License" "Apache-2.0"
			(at 0 0 90)
			(unlocked yes)
			(layer "B.Fab")
			(hide yes)
			(effects
				(font
					(size 1 1)
					(thickness 0.15)
				)
				(justify mirror)
			)
		)
		(sheetname "/Peripherals/")
		(sheetfile "peripherals.kicad_sch")
		(attr exclude_from_pos_files exclude_from_bom)
		(fp_circle
			(center 0 0)
			(end 0.475 0)
			(stroke
				(width 0.05)
				(type default)
			)
			(fill no)
			(layer "B.CrtYd")
		)
		(fp_text user "Author: Antmicro"
			(at -0.4 -3.901 90)
			(layer "B.Fab")
			(effects
				(font
					(size 0.7 0.7)
					(thickness 0.15)
				)
				(justify left bottom mirror)
			)
		)
		(fp_text user "${REFERENCE}"
			(at -0.4 -2.7 90)
			(layer "B.Fab")
			(effects
				(font
					(size 0.7 0.7)
					(thickness 0.15)
				)
				(justify left bottom mirror)
			)
		)
		(fp_text user "License: Apache-2.0"
			(at -0.4 -5.101 90)
			(layer "B.Fab")
			(effects
				(font
					(size 0.7 0.7)
					(thickness 0.15)
				)
				(justify left bottom mirror)
			)
		)
		(pad "1" smd circle
			(at 0 0 270)
			(size 0.75 0.75)
			(layers "B.Cu" "B.Mask")
			(net 97 "/Peripherals/FAN_PWM")
			(pinfunction "1")
			(pintype "passive")
		)
	)
	(footprint "antmicro-footprints:R_0402_1005Metric"
		(layer "B.Cu")
		(at 238.1 83.55 180)
		(descr "Resistor SMD 0402")
		(tags "resistor SMD 0402")
		(property "Reference" "R153"
			(at -1.625 -2.149999 0)
			(layer "B.SilkS")
			(effects
				(font
					(size 0.7 0.7)
					(thickness 0.15)
				)
				(justify left bottom mirror)
			)
		)
		(property "Value" "R_2k2_0402"
			(at -1.011843 -1.772046 0)
			(layer "B.Fab")
			(effects
				(font
					(size 0.7 0.7)
					(thickness 0.15)
				)
				(justify left bottom mirror)
			)
		)
		(property "Datasheet" "https://www.bourns.com/docs/product-datasheets/cr.pdf"
			(at 0 0 0)
			(layer "B.Fab")
			(hide yes)
			(effects
				(font
					(size 1.27 1.27)
					(thickness 0.15)
				)
				(justify mirror)
			)
		)
		(property "Description" "SMD Chip Resistor, 2.2 kohm, ± 1%, 62.5 mW, 0402 [1005 Metric], Thick Film, General Purpose"
			(at 0 0 0)
			(layer "B.Fab")
			(hide yes)
			(effects
				(font
					(size 1.27 1.27)
					(thickness 0.15)
				)
				(justify mirror)
			)
		)
		(property "Manufacturer" "Bourns"
			(at 0 0 0)
			(unlocked yes)
			(layer "B.Fab")
			(hide yes)
			(effects
				(font
					(size 1 1)
					(thickness 0.15)
				)
				(justify mirror)
			)
		)
		(property "MPN" "CR0402-FX-2201GLF"
			(at 0 0 0)
			(unlocked yes)
			(layer "B.Fab")
			(hide yes)
			(effects
				(font
					(size 1 1)
					(thickness 0.15)
				)
				(justify mirror)
			)
		)
		(property "Val" "2k2"
			(at 0 0 0)
			(unlocked yes)
			(layer "B.Fab")
			(hide yes)
			(effects
				(font
					(size 1 1)
					(thickness 0.15)
				)
				(justify mirror)
			)
		)
		(property "License" "Apache-2.0"
			(at 0 0 0)
			(unlocked yes)
			(layer "B.Fab")
			(hide yes)
			(effects
				(font
					(size 1 1)
					(thickness 0.15)
				)
				(justify mirror)
			)
		)
		(property "Author" "Antmicro"
			(at 0 0 0)
			(unlocked yes)
			(layer "B.Fab")
			(hide yes)
			(effects
				(font
					(size 1 1)
					(thickness 0.15)
				)
				(justify mirror)
			)
		)
		(property "Tolerance" "1%"
			(at 0 0 0)
			(unlocked yes)
			(layer "B.Fab")
			(hide yes)
			(effects
				(font
					(size 1 1)
					(thickness 0.15)
				)
				(justify mirror)
			)
		)
		(sheetname "/USB Debug, PD/")
		(sheetfile "usb_debug_pd.kicad_sch")
		(attr smd)
		(fp_poly
			(pts
				(xy -0.925 0.47) (xy -0.925 -0.47) (xy 0.925 -0.47) (xy 0.925 0.47)
			)
			(stroke
				(width 0.05)
				(type default)
			)
			(fill no)
			(layer "B.CrtYd")
		)
		(fp_poly
			(pts
				(xy -0.5 0.25) (xy -0.5 -0.25) (xy 0.5 -0.25) (xy 0.5 0.25)
			)
			(stroke
				(width 0.15)
				(type solid)
			)
			(fill no)
			(layer "B.Fab")
		)
		(fp_text user "${REFERENCE}"
			(at -0.95 -3.168 0)
			(layer "B.Fab")
			(effects
				(font
					(size 0.7 0.7)
					(thickness 0.15)
				)
				(justify left bottom mirror)
			)
		)
		(fp_text user "Author: Antmicro"
			(at -0.95 -4.169 0)
			(layer "B.Fab")
			(effects
				(font
					(size 0.7 0.7)
					(thickness 0.15)
				)
				(justify left bottom mirror)
			)
		)
		(fp_text user "License: Apache-2.0"
			(at -0.949999 -5.169 0)
			(layer "B.Fab")
			(effects
				(font
					(size 0.7 0.7)
					(thickness 0.15)
				)
				(justify left bottom mirror)
			)
		)
		(pad "1" smd roundrect
			(at -0.48 0 180)
			(size 0.59 0.64)
			(layers "B.Cu" "B.Mask" "B.Paste")
			(roundrect_rratio 0.25)
			(net 1 "GND")
			(pintype "passive")
		)
		(pad "2" smd roundrect
			(at 0.48 0 180)
			(size 0.59 0.64)
			(layers "B.Cu" "B.Mask" "B.Paste")
			(roundrect_rratio 0.25)
			(net 978 "/USB Debug, PD/USBC0_ISET")
			(pintype "passive")
		)
	)
	(footprint "antmicro-footprints:TP_SMD_0.75mm"
		(layer "B.Cu")
		(at 140.2 63.8 -90)
		(property "Reference" "TP97"
			(at 0.5 -0.3 90)
			(layer "B.SilkS")
			(effects
				(font
					(size 0.7 0.7)
					(thickness 0.15)
				)
				(justify left bottom mirror)
			)
		)
		(property "Value" "TP_0.75mm_SMD"
			(at 0 -1.2 90)
			(layer "B.Fab")
			(effects
				(font
					(size 0.7 0.7)
					(thickness 0.15)
				)
				(justify left bottom mirror)
			)
		)
		(property "Description" "SMT test point"
			(at 0 0 90)
			(layer "B.Fab")
			(hide yes)
			(effects
				(font
					(size 1.27 1.27)
					(thickness 0.15)
				)
				(justify mirror)
			)
		)
		(property "MPN" ""
			(at 0 0 90)
			(unlocked yes)
			(layer "B.Fab")
			(hide yes)
			(effects
				(font
					(size 1 1)
					(thickness 0.15)
				)
				(justify mirror)
			)
		)
		(property "Manufacturer" ""
			(at 0 0 90)
			(unlocked yes)
			(layer "B.Fab")
			(hide yes)
			(effects
				(font
					(size 1 1)
					(thickness 0.15)
				)
				(justify mirror)
			)
		)
		(property "Author" "Antmicro"
			(at 0 0 90)
			(unlocked yes)
			(layer "B.Fab")
			(hide yes)
			(effects
				(font
					(size 1 1)
					(thickness 0.15)
				)
				(justify mirror)
			)
		)
		(property "License" "Apache-2.0"
			(at 0 0 90)
			(unlocked yes)
			(layer "B.Fab")
			(hide yes)
			(effects
				(font
					(size 1 1)
					(thickness 0.15)
				)
				(justify mirror)
			)
		)
		(sheetname "/Peripherals/")
		(sheetfile "peripherals.kicad_sch")
		(attr exclude_from_pos_files exclude_from_bom)
		(fp_circle
			(center 0 0)
			(end 0.475 0)
			(stroke
				(width 0.05)
				(type default)
			)
			(fill no)
			(layer "B.CrtYd")
		)
		(fp_text user "Author: Antmicro"
			(at -0.4 -3.901 90)
			(layer "B.Fab")
			(effects
				(font
					(size 0.7 0.7)
					(thickness 0.15)
				)
				(justify left bottom mirror)
			)
		)
		(fp_text user "${REFERENCE}"
			(at -0.4 -2.7 90)
			(layer "B.Fab")
			(effects
				(font
					(size 0.7 0.7)
					(thickness 0.15)
				)
				(justify left bottom mirror)
			)
		)
		(fp_text user "License: Apache-2.0"
			(at -0.4 -5.101 90)
			(layer "B.Fab")
			(effects
				(font
					(size 0.7 0.7)
					(thickness 0.15)
				)
				(justify left bottom mirror)
			)
		)
		(pad "1" smd circle
			(at 0 0 270)
			(size 0.75 0.75)
			(layers "B.Cu" "B.Mask")
			(net 90 "/Peripherals/I2C_CONN_PEN")
			(pinfunction "1")
			(pintype "passive")
		)
	)
)
